(kicad_pcb
	(version 20260206)
	(generator "pcbnew")
	(generator_version "10.0")
	(general
		(thickness 1.6)
		(legacy_teardrops no)
	)
	(paper "A4")
	(title_block
		(title "03242023_DA0F0TMBIJ0_F0T_Motherboard_J_brd_V01_OCP.brd")
		(comment 1 "Grand Teton / footprints 175-181 of 6105")
	)
	(layers
		(0 "F.Cu" signal "TOP")
		(4 "In1.Cu" signal "GND")
		(6 "In2.Cu" signal "IN1")
		(8 "In3.Cu" signal "GND1")
		(10 "In4.Cu" signal "IN2")
		(12 "In5.Cu" signal "GND2")
		(14 "In6.Cu" signal "IN3")
		(16 "In7.Cu" signal "GND3")
		(18 "In8.Cu" signal "VCC")
		(20 "In9.Cu" signal "VCC1")
		(22 "In10.Cu" signal "GND4")
		(24 "In11.Cu" signal "IN4")
		(26 "In12.Cu" signal "GND5")
		(28 "In13.Cu" signal "IN5")
		(30 "In14.Cu" signal "GND6")
		(32 "In15.Cu" signal "IN6")
		(34 "In16.Cu" signal "GND7")
		(2 "B.Cu" signal "BOTTOM")
		(9 "F.Adhes" user "F.Adhesive")
		(11 "B.Adhes" user "B.Adhesive")
		(13 "F.Paste" user "Package Geometry/Pastemask Top")
		(15 "B.Paste" user "Package Geometry/Pastemask Bottom")
		(5 "F.SilkS" user "Ref Des/Silkscreen Top")
		(7 "B.SilkS" user "Ref Des/Silkscreen Bottom")
		(1 "F.Mask" user "Board Geometry/Soldermask Top")
		(3 "B.Mask" user "Board Geometry/Soldermask Bottom")
		(17 "Dwgs.User" user "User.Drawings")
		(19 "Cmts.User" user "User.Comments")
		(21 "Eco1.User" user "User.Eco1")
		(23 "Eco2.User" user "User.Eco2")
		(25 "Edge.Cuts" user "Board Geometry/Outline")
		(27 "Margin" user)
		(31 "F.CrtYd" user "Package Geometry/Place Bound Top")
		(29 "B.CrtYd" user "Package Geometry/Place Bound Bottom")
		(35 "F.Fab" user "Ref Des/Assembly Top")
		(33 "B.Fab" user "Ref Des/Assembly Bottom")
	)
	(footprint ""
		(layer "F.Cu")
		(at 424.223942 -402.671534 180)
		(property "Reference" "R3471"
			(at 0 0 180)
			(layer "F.SilkS")
			(hide yes)
			(effects
				(font
					(size 1.27 1.27)
				)
			)
		)
		(property "Value" ""
			(at 0 0 180)
			(layer "F.Fab")
			(effects
				(font
					(size 1.27 1.27)
				)
			)
		)
		(duplicate_pad_numbers_are_jumpers no)
		(fp_line
			(start 0.7874 0.4064)
			(end -0.7874 0.4064)
			(stroke
				(width 0.1524)
				(type default)
			)
			(layer "F.SilkS")
		)
		(fp_line
			(start 0.7874 -0.4064)
			(end 0.7874 0.4064)
			(stroke
				(width 0.1524)
				(type default)
			)
			(layer "F.SilkS")
		)
		(fp_line
			(start -0.7874 0.4064)
			(end -0.7874 -0.4064)
			(stroke
				(width 0.1524)
				(type default)
			)
			(layer "F.SilkS")
		)
		(fp_line
			(start -0.7874 -0.4064)
			(end 0.7874 -0.4064)
			(stroke
				(width 0.1524)
				(type default)
			)
			(layer "F.SilkS")
		)
		(fp_line
			(start 0.67945 0.3048)
			(end 0.120396 0.3048)
			(stroke
				(width 0.1)
				(type default)
			)
			(layer "F.Fab")
		)
		(fp_line
			(start 0.67945 -0.3048)
			(end 0.67945 0.3048)
			(stroke
				(width 0.1)
				(type default)
			)
			(layer "F.Fab")
		)
		(fp_line
			(start 0.12065 -0.2794)
			(end 0.12065 -0.3048)
			(stroke
				(width 0.1)
				(type default)
			)
			(layer "F.Fab")
		)
		(fp_line
			(start 0.12065 -0.3048)
			(end 0.67945 -0.3048)
			(stroke
				(width 0.1)
				(type default)
			)
			(layer "F.Fab")
		)
		(fp_line
			(start 0.120396 0.3048)
			(end 0.120396 0.2794)
			(stroke
				(width 0.1)
				(type default)
			)
			(layer "F.Fab")
		)
		(fp_line
			(start 0.120396 0.2794)
			(end -0.12065 0.2794)
			(stroke
				(width 0.1)
				(type default)
			)
			(layer "F.Fab")
		)
		(fp_line
			(start -0.12065 0.3048)
			(end -0.67945 0.3048)
			(stroke
				(width 0.1)
				(type default)
			)
			(layer "F.Fab")
		)
		(fp_line
			(start -0.12065 0.2794)
			(end -0.12065 0.3048)
			(stroke
				(width 0.1)
				(type default)
			)
			(layer "F.Fab")
		)
		(fp_line
			(start -0.12065 -0.2794)
			(end 0.12065 -0.2794)
			(stroke
				(width 0.1)
				(type default)
			)
			(layer "F.Fab")
		)
		(fp_line
			(start -0.12065 -0.305054)
			(end -0.12065 -0.2794)
			(stroke
				(width 0.1)
				(type default)
			)
			(layer "F.Fab")
		)
		(fp_line
			(start -0.67945 0.3048)
			(end -0.67945 -0.305054)
			(stroke
				(width 0.1)
				(type default)
			)
			(layer "F.Fab")
		)
		(fp_line
			(start -0.67945 -0.305054)
			(end -0.12065 -0.305054)
			(stroke
				(width 0.1)
				(type default)
			)
			(layer "F.Fab")
		)
		(pad "1" smd circle
			(at -0.40005 0 180)
			(size 0 0)
			(layers "F.Cu" "F.Mask" "F.Paste")
			(net "GPU_WP_HW_CTRL_N")
		)
		(pad "2" smd circle
			(at 0.40005 0 180)
			(size 0 0)
			(layers "F.Cu" "F.Mask" "F.Paste")
			(net "GND")
		)
	)
	(footprint ""
		(layer "F.Cu")
		(at 338.996528 -408.517344 -90)
		(property "Reference" "C924"
			(at 0 0 270)
			(layer "F.SilkS")
			(hide yes)
			(effects
				(font
					(size 1.27 1.27)
				)
			)
		)
		(property "Value" ""
			(at 0 0 270)
			(layer "F.Fab")
			(effects
				(font
					(size 1.27 1.27)
				)
			)
		)
		(duplicate_pad_numbers_are_jumpers no)
		(fp_line
			(start -0.299974 0.150114)
			(end -0.299974 -0.150114)
			(stroke
				(width 0.1)
				(type default)
			)
			(layer "F.Fab")
		)
		(fp_line
			(start 0.299974 0.150114)
			(end -0.299974 0.150114)
			(stroke
				(width 0.1)
				(type default)
			)
			(layer "F.Fab")
		)
		(fp_line
			(start -0.299974 -0.150114)
			(end 0.299974 -0.150114)
			(stroke
				(width 0.1)
				(type default)
			)
			(layer "F.Fab")
		)
		(fp_line
			(start 0.299974 -0.150114)
			(end 0.299974 0.150114)
			(stroke
				(width 0.1)
				(type default)
			)
			(layer "F.Fab")
		)
		(pad "1" smd rect
			(at -0.2667 0 270)
			(size 0.3048 0.381)
			(layers "F.Cu" "F.Mask" "F.Paste")
			(net "P5E_CPU0_PE0_TX_C_DN<4>")
		)
		(pad "2" smd rect
			(at 0.2667 0 270)
			(size 0.3048 0.381)
			(layers "F.Cu" "F.Mask" "F.Paste")
			(net "P5E_CPU0_PE0_TX_DN<4>")
		)
	)
	(footprint ""
		(layer "F.Cu")
		(at 192.052448 -402.128482 180)
		(property "Reference" "PR3928"
			(at 0 0 180)
			(layer "F.SilkS")
			(hide yes)
			(effects
				(font
					(size 1.27 1.27)
				)
			)
		)
		(property "Value" ""
			(at 0 0 180)
			(layer "F.Fab")
			(effects
				(font
					(size 1.27 1.27)
				)
			)
		)
		(duplicate_pad_numbers_are_jumpers no)
		(fp_line
			(start 0.7874 0.4064)
			(end -0.7874 0.4064)
			(stroke
				(width 0.1524)
				(type default)
			)
			(layer "F.SilkS")
		)
		(fp_line
			(start 0.7874 -0.4064)
			(end 0.7874 0.4064)
			(stroke
				(width 0.1524)
				(type default)
			)
			(layer "F.SilkS")
		)
		(fp_line
			(start -0.7874 0.4064)
			(end -0.7874 -0.4064)
			(stroke
				(width 0.1524)
				(type default)
			)
			(layer "F.SilkS")
		)
		(fp_line
			(start -0.7874 -0.4064)
			(end 0.7874 -0.4064)
			(stroke
				(width 0.1524)
				(type default)
			)
			(layer "F.SilkS")
		)
		(fp_line
			(start 0.67945 0.3048)
			(end 0.120396 0.3048)
			(stroke
				(width 0.1)
				(type default)
			)
			(layer "F.Fab")
		)
		(fp_line
			(start 0.67945 -0.3048)
			(end 0.67945 0.3048)
			(stroke
				(width 0.1)
				(type default)
			)
			(layer "F.Fab")
		)
		(fp_line
			(start 0.12065 -0.2794)
			(end 0.12065 -0.3048)
			(stroke
				(width 0.1)
				(type default)
			)
			(layer "F.Fab")
		)
		(fp_line
			(start 0.12065 -0.3048)
			(end 0.67945 -0.3048)
			(stroke
				(width 0.1)
				(type default)
			)
			(layer "F.Fab")
		)
		(fp_line
			(start 0.120396 0.3048)
			(end 0.120396 0.2794)
			(stroke
				(width 0.1)
				(type default)
			)
			(layer "F.Fab")
		)
		(fp_line
			(start 0.120396 0.2794)
			(end -0.12065 0.2794)
			(stroke
				(width 0.1)
				(type default)
			)
			(layer "F.Fab")
		)
		(fp_line
			(start -0.12065 0.3048)
			(end -0.67945 0.3048)
			(stroke
				(width 0.1)
				(type default)
			)
			(layer "F.Fab")
		)
		(fp_line
			(start -0.12065 0.2794)
			(end -0.12065 0.3048)
			(stroke
				(width 0.1)
				(type default)
			)
			(layer "F.Fab")
		)
		(fp_line
			(start -0.12065 -0.2794)
			(end 0.12065 -0.2794)
			(stroke
				(width 0.1)
				(type default)
			)
			(layer "F.Fab")
		)
		(fp_line
			(start -0.12065 -0.305054)
			(end -0.12065 -0.2794)
			(stroke
				(width 0.1)
				(type default)
			)
			(layer "F.Fab")
		)
		(fp_line
			(start -0.67945 0.3048)
			(end -0.67945 -0.305054)
			(stroke
				(width 0.1)
				(type default)
			)
			(layer "F.Fab")
		)
		(fp_line
			(start -0.67945 -0.305054)
			(end -0.12065 -0.305054)
			(stroke
				(width 0.1)
				(type default)
			)
			(layer "F.Fab")
		)
		(pad "1" smd circle
			(at -0.40005 0 180)
			(size 0 0)
			(layers "F.Cu" "F.Mask" "F.Paste")
			(net "HSC_ON")
		)
		(pad "2" smd circle
			(at 0.40005 0 180)
			(size 0 0)
			(layers "F.Cu" "F.Mask" "F.Paste")
			(net "HSC_ON_R")
		)
	)
	(footprint ""
		(layer "F.Cu")
		(at 385.699 -69.179948 180)
		(property "Reference" "R775"
			(at 0 0 180)
			(layer "F.SilkS")
			(hide yes)
			(effects
				(font
					(size 1.27 1.27)
				)
			)
		)
		(property "Value" ""
			(at 0 0 180)
			(layer "F.Fab")
			(effects
				(font
					(size 1.27 1.27)
				)
			)
		)
		(duplicate_pad_numbers_are_jumpers no)
		(fp_line
			(start 0.7874 0.4064)
			(end -0.7874 0.4064)
			(stroke
				(width 0.1524)
				(type default)
			)
			(layer "F.SilkS")
		)
		(fp_line
			(start 0.7874 -0.4064)
			(end 0.7874 0.4064)
			(stroke
				(width 0.1524)
				(type default)
			)
			(layer "F.SilkS")
		)
		(fp_line
			(start -0.7874 0.4064)
			(end -0.7874 -0.4064)
			(stroke
				(width 0.1524)
				(type default)
			)
			(layer "F.SilkS")
		)
		(fp_line
			(start -0.7874 -0.4064)
			(end 0.7874 -0.4064)
			(stroke
				(width 0.1524)
				(type default)
			)
			(layer "F.SilkS")
		)
		(fp_line
			(start 0.67945 0.3048)
			(end 0.120396 0.3048)
			(stroke
				(width 0.1)
				(type default)
			)
			(layer "F.Fab")
		)
		(fp_line
			(start 0.67945 -0.3048)
			(end 0.67945 0.3048)
			(stroke
				(width 0.1)
				(type default)
			)
			(layer "F.Fab")
		)
		(fp_line
			(start 0.12065 -0.2794)
			(end 0.12065 -0.3048)
			(stroke
				(width 0.1)
				(type default)
			)
			(layer "F.Fab")
		)
		(fp_line
			(start 0.12065 -0.3048)
			(end 0.67945 -0.3048)
			(stroke
				(width 0.1)
				(type default)
			)
			(layer "F.Fab")
		)
		(fp_line
			(start 0.120396 0.3048)
			(end 0.120396 0.2794)
			(stroke
				(width 0.1)
				(type default)
			)
			(layer "F.Fab")
		)
		(fp_line
			(start 0.120396 0.2794)
			(end -0.12065 0.2794)
			(stroke
				(width 0.1)
				(type default)
			)
			(layer "F.Fab")
		)
		(fp_line
			(start -0.12065 0.3048)
			(end -0.67945 0.3048)
			(stroke
				(width 0.1)
				(type default)
			)
			(layer "F.Fab")
		)
		(fp_line
			(start -0.12065 0.2794)
			(end -0.12065 0.3048)
			(stroke
				(width 0.1)
				(type default)
			)
			(layer "F.Fab")
		)
		(fp_line
			(start -0.12065 -0.2794)
			(end 0.12065 -0.2794)
			(stroke
				(width 0.1)
				(type default)
			)
			(layer "F.Fab")
		)
		(fp_line
			(start -0.12065 -0.305054)
			(end -0.12065 -0.2794)
			(stroke
				(width 0.1)
				(type default)
			)
			(layer "F.Fab")
		)
		(fp_line
			(start -0.67945 0.3048)
			(end -0.67945 -0.305054)
			(stroke
				(width 0.1)
				(type default)
			)
			(layer "F.Fab")
		)
		(fp_line
			(start -0.67945 -0.305054)
			(end -0.12065 -0.305054)
			(stroke
				(width 0.1)
				(type default)
			)
			(layer "F.Fab")
		)
		(pad "1" smd circle
			(at -0.40005 0 180)
			(size 0 0)
			(layers "F.Cu" "F.Mask" "F.Paste")
			(net "JTAG_DBP_TMS_R")
		)
		(pad "2" smd circle
			(at 0.40005 0 180)
			(size 0 0)
			(layers "F.Cu" "F.Mask" "F.Paste")
			(net "JTAG_DBP_TMS")
		)
	)
	(footprint ""
		(layer "F.Cu")
		(at 128.778 -73.370948)
		(property "Reference" "R2507"
			(at 0 0 0)
			(layer "F.SilkS")
			(hide yes)
			(effects
				(font
					(size 1.27 1.27)
				)
			)
		)
		(property "Value" ""
			(at 0 0 0)
			(layer "F.Fab")
			(effects
				(font
					(size 1.27 1.27)
				)
			)
		)
		(duplicate_pad_numbers_are_jumpers no)
		(fp_line
			(start -0.7874 -0.4064)
			(end 0.7874 -0.4064)
			(stroke
				(width 0.1524)
				(type default)
			)
			(layer "F.SilkS")
		)
		(fp_line
			(start -0.7874 0.4064)
			(end -0.7874 -0.4064)
			(stroke
				(width 0.1524)
				(type default)
			)
			(layer "F.SilkS")
		)
		(fp_line
			(start 0.7874 -0.4064)
			(end 0.7874 0.4064)
			(stroke
				(width 0.1524)
				(type default)
			)
			(layer "F.SilkS")
		)
		(fp_line
			(start 0.7874 0.4064)
			(end -0.7874 0.4064)
			(stroke
				(width 0.1524)
				(type default)
			)
			(layer "F.SilkS")
		)
		(fp_line
			(start -0.67945 -0.305054)
			(end -0.12065 -0.305054)
			(stroke
				(width 0.1)
				(type default)
			)
			(layer "F.Fab")
		)
		(fp_line
			(start -0.67945 0.3048)
			(end -0.67945 -0.305054)
			(stroke
				(width 0.1)
				(type default)
			)
			(layer "F.Fab")
		)
		(fp_line
			(start -0.12065 -0.305054)
			(end -0.12065 -0.2794)
			(stroke
				(width 0.1)
				(type default)
			)
			(layer "F.Fab")
		)
		(fp_line
			(start -0.12065 -0.2794)
			(end 0.12065 -0.2794)
			(stroke
				(width 0.1)
				(type default)
			)
			(layer "F.Fab")
		)
		(fp_line
			(start -0.12065 0.2794)
			(end -0.12065 0.3048)
			(stroke
				(width 0.1)
				(type default)
			)
			(layer "F.Fab")
		)
		(fp_line
			(start -0.12065 0.3048)
			(end -0.67945 0.3048)
			(stroke
				(width 0.1)
				(type default)
			)
			(layer "F.Fab")
		)
		(fp_line
			(start 0.120396 0.2794)
			(end -0.12065 0.2794)
			(stroke
				(width 0.1)
				(type default)
			)
			(layer "F.Fab")
		)
		(fp_line
			(start 0.120396 0.3048)
			(end 0.120396 0.2794)
			(stroke
				(width 0.1)
				(type default)
			)
			(layer "F.Fab")
		)
		(fp_line
			(start 0.12065 -0.3048)
			(end 0.67945 -0.3048)
			(stroke
				(width 0.1)
				(type default)
			)
			(layer "F.Fab")
		)
		(fp_line
			(start 0.12065 -0.2794)
			(end 0.12065 -0.3048)
			(stroke
				(width 0.1)
				(type default)
			)
			(layer "F.Fab")
		)
		(fp_line
			(start 0.67945 -0.3048)
			(end 0.67945 0.3048)
			(stroke
				(width 0.1)
				(type default)
			)
			(layer "F.Fab")
		)
		(fp_line
			(start 0.67945 0.3048)
			(end 0.120396 0.3048)
			(stroke
				(width 0.1)
				(type default)
			)
			(layer "F.Fab")
		)
		(pad "1" smd circle
			(at -0.40005 0)
			(size 0 0)
			(layers "F.Cu" "F.Mask" "F.Paste")
			(net "P3V3_AUX")
		)
		(pad "2" smd circle
			(at 0.40005 0)
			(size 0 0)
			(layers "F.Cu" "F.Mask" "F.Paste")
			(net "JTAG_BMC_DBP_TDI")
		)
	)
	(footprint ""
		(layer "F.Cu")
		(at 25.9715 -397.688562 90)
		(property "Reference" "R4665"
			(at 0 0 90)
			(layer "F.SilkS")
			(hide yes)
			(effects
				(font
					(size 1.27 1.27)
				)
			)
		)
		(property "Value" ""
			(at 0 0 90)
			(layer "F.Fab")
			(effects
				(font
					(size 1.27 1.27)
				)
			)
		)
		(duplicate_pad_numbers_are_jumpers no)
		(fp_line
			(start -0.013462 -0.4064)
			(end 0.7874 -0.4064)
			(stroke
				(width 0.1524)
				(type default)
			)
			(layer "F.SilkS")
		)
		(fp_line
			(start 0.7874 0.4064)
			(end -0.7874 0.4064)
			(stroke
				(width 0.1524)
				(type default)
			)
			(layer "F.SilkS")
		)
		(fp_line
			(start -0.7874 0.4064)
			(end -0.7874 -0.4064)
			(stroke
				(width 0.1524)
				(type default)
			)
			(layer "F.SilkS")
		)
		(fp_line
			(start -0.12065 -0.305054)
			(end -0.12065 -0.2794)
			(stroke
				(width 0.1)
				(type default)
			)
			(layer "F.Fab")
		)
		(fp_line
			(start -0.67945 -0.305054)
			(end -0.12065 -0.305054)
			(stroke
				(width 0.1)
				(type default)
			)
			(layer "F.Fab")
		)
		(fp_line
			(start 0.67945 -0.3048)
			(end 0.67945 0.3048)
			(stroke
				(width 0.1)
				(type default)
			)
			(layer "F.Fab")
		)
		(fp_line
			(start 0.12065 -0.3048)
			(end 0.67945 -0.3048)
			(stroke
				(width 0.1)
				(type default)
			)
			(layer "F.Fab")
		)
		(fp_line
			(start 0.12065 -0.2794)
			(end 0.12065 -0.3048)
			(stroke
				(width 0.1)
				(type default)
			)
			(layer "F.Fab")
		)
		(fp_line
			(start -0.12065 -0.2794)
			(end 0.12065 -0.2794)
			(stroke
				(width 0.1)
				(type default)
			)
			(layer "F.Fab")
		)
		(fp_line
			(start 0.120396 0.2794)
			(end -0.12065 0.2794)
			(stroke
				(width 0.1)
				(type default)
			)
			(layer "F.Fab")
		)
		(fp_line
			(start -0.12065 0.2794)
			(end -0.12065 0.3048)
			(stroke
				(width 0.1)
				(type default)
			)
			(layer "F.Fab")
		)
		(fp_line
			(start 0.67945 0.3048)
			(end 0.120396 0.3048)
			(stroke
				(width 0.1)
				(type default)
			)
			(layer "F.Fab")
		)
		(fp_line
			(start 0.120396 0.3048)
			(end 0.120396 0.2794)
			(stroke
				(width 0.1)
				(type default)
			)
			(layer "F.Fab")
		)
		(fp_line
			(start -0.12065 0.3048)
			(end -0.67945 0.3048)
			(stroke
				(width 0.1)
				(type default)
			)
			(layer "F.Fab")
		)
		(fp_line
			(start -0.67945 0.3048)
			(end -0.67945 -0.305054)
			(stroke
				(width 0.1)
				(type default)
			)
			(layer "F.Fab")
		)
		(pad "1" smd rect
			(at -0.40005 0 270)
			(size 0.4572 0.508)
			(layers "F.Cu" "F.Mask" "F.Paste")
			(net "P2E_MB_BMC_RX_DP<0>")
		)
		(pad "2" smd rect
			(at 0.40005 0 270)
			(size 0.4572 0.508)
			(layers "F.Cu" "F.Mask" "F.Paste")
			(net "P2E_MB_BMC_RX_R2_DP<0>")
		)
	)
	(footprint ""
		(layer "F.Cu")
		(at 220.087444 -99.21748)
		(property "Reference" "C2394"
			(at 0 0 0)
			(layer "F.SilkS")
			(hide yes)
			(effects
				(font
					(size 1.27 1.27)
				)
			)
		)
		(property "Value" ""
			(at 0 0 0)
			(layer "F.Fab")
			(effects
				(font
					(size 1.27 1.27)
				)
			)
		)
		(duplicate_pad_numbers_are_jumpers no)
		(fp_line
			(start -0.7874 -0.4064)
			(end 0.7874 -0.4064)
			(stroke
				(width 0.1524)
				(type default)
			)
			(layer "F.SilkS")
		)
		(fp_line
			(start -0.7874 0.4064)
			(end -0.7874 -0.4064)
			(stroke
				(width 0.1524)
				(type default)
			)
			(layer "F.SilkS")
		)
		(fp_line
			(start 0.7874 -0.4064)
			(end 0.7874 0.4064)
			(stroke
				(width 0.1524)
				(type default)
			)
			(layer "F.SilkS")
		)
		(fp_line
			(start 0.7874 0.4064)
			(end -0.7874 0.4064)
			(stroke
				(width 0.1524)
				(type default)
			)
			(layer "F.SilkS")
		)
		(fp_line
			(start -0.67945 -0.305054)
			(end -0.12065 -0.305054)
			(stroke
				(width 0.1)
				(type default)
			)
			(layer "F.Fab")
		)
		(fp_line
			(start -0.67945 0.3048)
			(end -0.67945 -0.305054)
			(stroke
				(width 0.1)
				(type default)
			)
			(layer "F.Fab")
		)
		(fp_line
			(start -0.12065 -0.305054)
			(end -0.12065 -0.2794)
			(stroke
				(width 0.1)
				(type default)
			)
			(layer "F.Fab")
		)
		(fp_line
			(start -0.12065 -0.2794)
			(end 0.12065 -0.2794)
			(stroke
				(width 0.1)
				(type default)
			)
			(layer "F.Fab")
		)
		(fp_line
			(start -0.12065 0.2794)
			(end -0.12065 0.3048)
			(stroke
				(width 0.1)
				(type default)
			)
			(layer "F.Fab")
		)
		(fp_line
			(start -0.12065 0.3048)
			(end -0.67945 0.3048)
			(stroke
				(width 0.1)
				(type default)
			)
			(layer "F.Fab")
		)
		(fp_line
			(start 0.120396 0.2794)
			(end -0.12065 0.2794)
			(stroke
				(width 0.1)
				(type default)
			)
			(layer "F.Fab")
		)
		(fp_line
			(start 0.120396 0.3048)
			(end 0.120396 0.2794)
			(stroke
				(width 0.1)
				(type default)
			)
			(layer "F.Fab")
		)
		(fp_line
			(start 0.12065 -0.3048)
			(end 0.67945 -0.3048)
			(stroke
				(width 0.1)
				(type default)
			)
			(layer "F.Fab")
		)
		(fp_line
			(start 0.12065 -0.2794)
			(end 0.12065 -0.3048)
			(stroke
				(width 0.1)
				(type default)
			)
			(layer "F.Fab")
		)
		(fp_line
			(start 0.67945 -0.3048)
			(end 0.67945 0.3048)
			(stroke
				(width 0.1)
				(type default)
			)
			(layer "F.Fab")
		)
		(fp_line
			(start 0.67945 0.3048)
			(end 0.120396 0.3048)
			(stroke
				(width 0.1)
				(type default)
			)
			(layer "F.Fab")
		)
		(pad "1" smd circle
			(at -0.40005 0)
			(size 0 0)
			(layers "F.Cu" "F.Mask" "F.Paste")
			(net "U206_VDD")
		)
		(pad "2" smd circle
			(at 0.40005 0)
			(size 0 0)
			(layers "F.Cu" "F.Mask" "F.Paste")
			(net "GND")
		)
	)
)
